(kicad_pcb
	(version 20211014)
	(generator pcbnew)
	(general
    (thickness 1.6)
  )
	(paper "A4")
	(title_block
    (title "SA800U (Snapdragon 845) Baseboard")
    (date "2023-10-19")
    (rev "1.0.3")
    (company "Antmicro Ltd.")
    (comment 1 "www.antmicro.com")
		(comment 9 "footprints 428-434 of 589")
	)
	(layers
    (0 "F.Cu" signal)
    (1 "In1.Cu" power)
    (2 "In2.Cu" signal)
    (3 "In3.Cu" signal)
    (4 "In4.Cu" power)
    (31 "B.Cu" signal)
    (32 "B.Adhes" user "B.Adhesive")
    (33 "F.Adhes" user "F.Adhesive")
    (34 "B.Paste" user)
    (35 "F.Paste" user)
    (36 "B.SilkS" user "B.Silkscreen")
    (37 "F.SilkS" user "F.Silkscreen")
    (38 "B.Mask" user)
    (39 "F.Mask" user)
    (40 "Dwgs.User" user "User.Drawings")
    (41 "Cmts.User" user "User.Comments")
    (42 "Eco1.User" user "User.Eco1")
    (43 "Eco2.User" user "User.Eco2")
    (44 "Edge.Cuts" user)
    (45 "Margin" user)
    (46 "B.CrtYd" user "B.Courtyard")
    (47 "F.CrtYd" user "F.Courtyard")
    (48 "B.Fab" user)
    (49 "F.Fab" user)
  )
	(footprint "sa800u-baseboard-hw-footprints:R_0402_1005Metric" (layer "B.Cu")
    (tedit 5FD9C158)
    (at 75.6 120.25)
    (descr "Resistor SMD 0402")
    (tags "resistor SMD 0402")
    (property "Author" "Antmicro")
    (property "License" "Apache-2.0")
    (property "MPN" "CR0402-FX-7501GLF")
    (property "Manufacturer" "Bourns")
    (property "Sheetfile" "psu.kicad_sch")
    (property "Sheetname" "PSU")
    (property "Tolerance" "1%")
    (property "Val" "7k5")
    (attr smd)
    (fp_text reference "R123" (at -0.21 -4.79 180) (layer "B.SilkS")
      (effects (font (size 0.7 0.7) (thickness 0.15)) (justify left bottom mirror))
    )
    (fp_text value "R_7k5_0402" (at 0 -1.4 180) (layer "B.Fab")
      (effects (font (size 0.7 0.7) (thickness 0.15)) (justify left bottom mirror))
    )
    (fp_text user "Author: Antmicro" (at -0.95 -4.169 180) (layer "B.Fab") hide
      (effects (font (size 0.7 0.7) (thickness 0.15)) (justify left bottom mirror))
    )
    (fp_text user "${REFERENCE}" (at -0.95 -3.168 180) (layer "B.Fab") hide
      (effects (font (size 0.7 0.7) (thickness 0.15)) (justify left bottom mirror))
    )
    (fp_text user "License: Apache-2.0" (at -0.95 -5.169 180) (layer "B.Fab") hide
      (effects (font (size 0.7 0.7) (thickness 0.15)) (justify left bottom mirror))
    )
    (fp_rect (start -0.93 0.47) (end 0.93 -0.47) (layer "B.CrtYd") (width 0.05) (fill none))
    (fp_rect (start -0.5 0.25) (end 0.5 -0.25) (layer "B.Fab") (width 0.15) (fill none))
    (pad "1" smd roundrect (at -0.485 0) (size 0.59 0.64) (layers "B.Cu" "B.Paste" "B.Mask") (roundrect_rratio 0.25)
      (net 74 "VDD") (pintype "passive"))
    (pad "2" smd roundrect (at 0.485 0) (size 0.59 0.64) (layers "B.Cu" "B.Paste" "B.Mask") (roundrect_rratio 0.25)
      (net 405 "Net-(R123-Pad2)") (pintype "passive"))
  )
	(footprint "sa800u-baseboard-hw-footprints:C_0402_1005Metric" (layer "B.Cu")
    (tedit 616D63CF)
    (at 72.7 102.2 90)
    (descr "Capacitor SMD 0402")
    (tags "capacitor SMD 0402")
    (property "Author" "Antmicro")
    (property "Dielectric" "")
    (property "License" "Apache-2.0")
    (property "MPN" "C1005X6S1A105K050BC")
    (property "Manufacturer" "TDK")
    (property "Sheetfile" "poe.kicad_sch")
    (property "Sheetname" "PoE")
    (property "Val" "1u")
    (property "Voltage" "")
    (attr smd)
    (fp_text reference "C150" (at 1.46 -1.67 270) (layer "B.SilkS")
      (effects (font (size 0.7 0.7) (thickness 0.15)) (justify left bottom mirror))
    )
    (fp_text value "C_1u_0402" (at 0 -1.4 270) (layer "B.Fab")
      (effects (font (size 0.7 0.7) (thickness 0.15)) (justify left bottom mirror))
    )
    (fp_text user "${REFERENCE}" (at -0.932 -3.168 270) (layer "B.Fab") hide
      (effects (font (size 0.7 0.7) (thickness 0.15)) (justify left bottom mirror))
    )
    (fp_text user "License: Apache-2.0" (at -0.932 -5.17 270) (layer "B.Fab") hide
      (effects (font (size 0.7 0.7) (thickness 0.15)) (justify left bottom mirror))
    )
    (fp_text user "Author: Antmicro" (at -0.932 -4.17 270) (layer "B.Fab") hide
      (effects (font (size 0.7 0.7) (thickness 0.15)) (justify left bottom mirror))
    )
    (fp_rect (start -0.94 0.47) (end 0.94 -0.47) (layer "B.CrtYd") (width 0.05) (fill none))
    (fp_rect (start -0.499 0.249) (end 0.499 -0.249) (layer "B.Fab") (width 0.15) (fill none))
    (pad "1" smd roundrect (at -0.484 0 90) (size 0.59 0.64) (layers "B.Cu" "B.Paste" "B.Mask") (roundrect_rratio 0.25)
      (net 136 "5V_POE") (pintype "passive"))
    (pad "2" smd roundrect (at 0.484 0 90) (size 0.59 0.64) (layers "B.Cu" "B.Paste" "B.Mask") (roundrect_rratio 0.25)
      (net 1 "GND") (pintype "passive"))
  )
	(footprint "sa800u-baseboard-hw-footprints:PowerPak-1212" (layer "B.Cu")
    (tedit 625E61BE)
    (at 74.75 106.9)
    (property "Author" "Antmicro")
    (property "License" "Apache-2.0")
    (property "MPN" "SI7223DN-T1-GE3")
    (property "Manufacturer" "Vishay")
    (property "Sheetfile" "psu.kicad_sch")
    (property "Sheetname" "PSU")
    (attr smd)
    (fp_text reference "Q12" (at 0 2.5 180) (layer "B.SilkS")
      (effects (font (size 0.65 0.65) (thickness 0.15)) (justify mirror))
    )
    (fp_text value "Si7223DN" (at 0 -3 180) (layer "B.Fab") hide
      (effects (font (size 0.65 0.65) (thickness 0.15)) (justify mirror))
    )
    (fp_text user "License: Apache-2.0" (at -2.667 -8.599 180) (layer "B.Fab") hide
      (effects (font (size 0.7 0.7) (thickness 0.15)) (justify left bottom mirror))
    )
    (fp_text user "${REFERENCE}" (at 0 0 180) (layer "B.Fab") hide
      (effects (font (size 0.65 0.65) (thickness 0.15)) (justify mirror))
    )
    (fp_text user "Author: Antmicro" (at -2.667 -7.4 180) (layer "B.Fab") hide
      (effects (font (size 0.7 0.7) (thickness 0.15)) (justify left bottom mirror))
    )
    (fp_poly (pts
        (xy 1.699 0.122)
        (xy 1.699 0.529)
        (xy 1.14 0.529)
        (xy 1.14 0.772)
        (xy 1.699 0.772)
        (xy 1.699 1.179)
        (xy 1.14 1.179)
        (xy 1.14 1.12)
        (xy -0.047 1.12)
        (xy -0.047 1.7)
        (xy -0.387 1.7)
        (xy -0.387 1.12)
        (xy -0.386607 0.174507)
        (xy 1.14 0.175)
        (xy 1.14 0.122)
      ) (layer "B.Paste") (width 0.1) (fill solid))
    (fp_poly (pts
        (xy 1.699 -1.178)
        (xy 1.699 -0.771)
        (xy 1.14 -0.771)
        (xy 1.14 -0.528)
        (xy 1.699 -0.528)
        (xy 1.699 -0.121)
        (xy 1.14 -0.121)
        (xy 1.14 -0.174)
        (xy -0.387 -0.174)
        (xy -0.387 -1.119)
        (xy -0.386607 -1.698508)
        (xy -0.047 -1.699)
        (xy -0.047 -1.119)
        (xy 1.14 -1.119)
        (xy 1.14 -1.178)
      ) (layer "B.Paste") (width 0.1) (fill solid))
    (fp_line (start 1.701 1.702) (end 1.701 1.511) (layer "B.SilkS") (width 0.15))
    (fp_line (start -1.702 1.511) (end -1.702 1.702) (layer "B.SilkS") (width 0.15))
    (fp_line (start -1.702 -1.701) (end -1.702 -1.51) (layer "B.SilkS") (width 0.15))
    (fp_line (start 0.2 1.702) (end 1.701 1.702) (layer "B.SilkS") (width 0.15))
    (fp_line (start 1.701 -1.51) (end 1.701 -1.701) (layer "B.SilkS") (width 0.15))
    (fp_line (start 1.701 -1.701) (end 0.2 -1.7) (layer "B.SilkS") (width 0.15))
    (fp_line (start -0.6 -1.7) (end -1.702 -1.701) (layer "B.SilkS") (width 0.15))
    (fp_line (start -1.702 1.702) (end -0.6 1.7) (layer "B.SilkS") (width 0.15))
    (fp_circle (center -1.85 1.3) (end -1.8 1.3) (layer "B.SilkS") (width 0.15) (fill solid))
    (fp_poly (pts
        (xy 1.699 1.179)
        (xy 1.14 1.179)
        (xy 1.14 1.12)
        (xy -0.047 1.12)
        (xy -0.047 1.7)
        (xy -0.387 1.7)
        (xy -0.387 0.175)
        (xy 1.14 0.175)
        (xy 1.14 0.122)
        (xy 1.699 0.122)
        (xy 1.699 0.529)
        (xy 1.14 0.529)
        (xy 1.14 0.772)
        (xy 1.699 0.772)
      ) (layer "B.Mask") (width 0.1) (fill solid))
    (fp_poly (pts
        (xy -0.387 -0.174)
        (xy -0.387 -1.699)
        (xy -0.047 -1.699)
        (xy -0.047 -1.119)
        (xy 1.14 -1.119)
        (xy 1.14 -1.178)
        (xy 1.699 -1.178)
        (xy 1.699 -0.771)
        (xy 1.14 -0.771)
        (xy 1.14 -0.528)
        (xy 1.699 -0.528)
        (xy 1.699 -0.121)
        (xy 1.14 -0.121)
        (xy 1.14 -0.174)
      ) (layer "B.Mask") (width 0.1) (fill solid))
    (fp_line (start 1.95 -1.95) (end -1.96 -1.95) (layer "B.CrtYd") (width 0.05))
    (fp_line (start -1.96 -1.95) (end -1.96 1.96) (layer "B.CrtYd") (width 0.05))
    (fp_line (start 1.95 1.96) (end 1.95 -1.95) (layer "B.CrtYd") (width 0.05))
    (fp_line (start -1.96 1.96) (end 1.95 1.96) (layer "B.CrtYd") (width 0.05))
    (fp_line (start -1.575 1.575) (end 1.574 1.575) (layer "B.Fab") (width 0.15))
    (fp_line (start -1.575 -1.574) (end -1.575 1.575) (layer "B.Fab") (width 0.15))
    (fp_line (start 1.574 -1.574) (end -1.575 -1.574) (layer "B.Fab") (width 0.15))
    (fp_line (start 1.574 1.575) (end 1.574 -1.574) (layer "B.Fab") (width 0.15))
    (fp_circle (center 0.99 0.975) (end 0.914 0.975) (layer "B.Fab") (width 0.15) (fill none))
    (pad "1" smd rect (at -1.446 0.975) (size 0.508 0.4064) (layers "B.Cu" "B.Paste" "B.Mask")
      (net 159 "/PSU/VS3") (pinfunction "S1") (pintype "passive"))
    (pad "2" smd rect (at -1.446 0.325) (size 0.508 0.4064) (layers "B.Cu" "B.Paste" "B.Mask")
      (net 367 "/PSU/G3") (pinfunction "G1") (pintype "passive"))
    (pad "3" smd rect (at -1.446 -0.324) (size 0.508 0.4064) (layers "B.Cu" "B.Paste" "B.Mask")
      (net 159 "/PSU/VS3") (pinfunction "S2") (pintype "passive"))
    (pad "4" smd rect (at -1.446 -0.974) (size 0.508 0.4064) (layers "B.Cu" "B.Paste" "B.Mask")
      (net 367 "/PSU/G3") (pinfunction "G2") (pintype "passive"))
    (pad "5" smd rect (at 1.42 -0.974) (size 0.5588 0.4064) (layers "B.Cu" "B.Paste" "B.Mask")
      (net 136 "5V_POE") (pinfunction "D2") (pintype "passive"))
    (pad "6" smd custom (at 1.42 -0.324) (size 0.5588 0.4064) (layers "B.Cu" "B.Paste" "B.Mask")
      (net 136 "5V_POE") (pinfunction "D2") (pintype "passive") (zone_connect 2)
      (options (clearance outline) (anchor rect))
      (primitives
        (gr_poly (pts
            (xy 0.2794 -0.853186)
            (xy 0.2794 -0.446786)
            (xy -0.2794 -0.446786)
            (xy -0.2794 -0.2032)
            (xy 0.2794 -0.2032)
            (xy 0.2794 0.2032)
            (xy -0.2794 0.2032)
            (xy -0.279407 0.150493)
            (xy -1.806607 0.150493)
            (xy -1.806607 -1.374508)
            (xy -1.466602 -1.374508)
            (xy -1.466602 -0.794499)
            (xy -0.279407 -0.794507)
            (xy -0.2794 -0.853186)
          ) (width 0.1) (fill yes))
      ))
    (pad "7" smd custom (at 1.42 0.325) (size 0.5588 0.4064) (layers "B.Cu" "B.Paste" "B.Mask")
      (net 74 "VDD") (pinfunction "D1") (pintype "passive") (zone_connect 2)
      (options (clearance outline) (anchor rect))
      (primitives
        (gr_poly (pts
            (xy 0.2794 0.446786)
            (xy 0.2794 0.853186)
            (xy -0.2794 0.853186)
            (xy -0.279407 0.794507)
            (xy -1.466602 0.794499)
            (xy -1.466602 1.374508)
            (xy -1.806607 1.374508)
            (xy -1.806607 -0.150493)
            (xy -0.279407 -0.150493)
            (xy -0.2794 -0.2032)
            (xy 0.2794 -0.2032)
            (xy 0.2794 0.2032)
            (xy -0.2794 0.2032)
            (xy -0.2794 0.446786)
          ) (width 0.1) (fill yes))
      ))
    (pad "8" smd rect (at 1.42 0.975) (size 0.5588 0.4064) (layers "B.Cu" "B.Paste" "B.Mask")
      (net 74 "VDD") (pinfunction "D1") (pintype "passive"))
  )
	(footprint "sa800u-baseboard-hw-footprints:C_0402_1005Metric" (layer "B.Cu")
    (tedit 616D63CF)
    (at 73.6 125.15)
    (descr "Capacitor SMD 0402")
    (tags "capacitor SMD 0402")
    (property "Author" "Antmicro")
    (property "Dielectric" "X5R")
    (property "License" "Apache-2.0")
    (property "MPN" "GRM155R61H104KE14D")
    (property "Manufacturer" "Murata")
    (property "Sheetfile" "psu.kicad_sch")
    (property "Sheetname" "PSU")
    (property "Val" "100n")
    (property "Voltage" "50V")
    (attr smd)
    (fp_text reference "C123" (at 1.71 3.35 180) (layer "B.SilkS")
      (effects (font (size 0.7 0.7) (thickness 0.15)) (justify left bottom mirror))
    )
    (fp_text value "C_100n_0402" (at 0 -1.4 180) (layer "B.Fab")
      (effects (font (size 0.7 0.7) (thickness 0.15)) (justify left bottom mirror))
    )
    (fp_text user "${REFERENCE}" (at -0.932 -3.168 180) (layer "B.Fab") hide
      (effects (font (size 0.7 0.7) (thickness 0.15)) (justify left bottom mirror))
    )
    (fp_text user "License: Apache-2.0" (at -0.932 -5.17 180) (layer "B.Fab") hide
      (effects (font (size 0.7 0.7) (thickness 0.15)) (justify left bottom mirror))
    )
    (fp_text user "Author: Antmicro" (at -0.932 -4.17 180) (layer "B.Fab") hide
      (effects (font (size 0.7 0.7) (thickness 0.15)) (justify left bottom mirror))
    )
    (fp_rect (start -0.94 0.47) (end 0.94 -0.47) (layer "B.CrtYd") (width 0.05) (fill none))
    (fp_rect (start -0.499 0.249) (end 0.499 -0.249) (layer "B.Fab") (width 0.15) (fill none))
    (pad "1" smd roundrect (at -0.484 0) (size 0.59 0.64) (layers "B.Cu" "B.Paste" "B.Mask") (roundrect_rratio 0.25)
      (net 354 "/PSU/G1") (pintype "passive"))
    (pad "2" smd roundrect (at 0.484 0) (size 0.59 0.64) (layers "B.Cu" "B.Paste" "B.Mask") (roundrect_rratio 0.25)
      (net 1 "GND") (pintype "passive"))
  )
	(footprint "sa800u-baseboard-hw-footprints:C_0402_1005Metric" (layer "B.Cu")
    (tedit 616D63CF)
    (at 73.6 124.15)
    (descr "Capacitor SMD 0402")
    (tags "capacitor SMD 0402")
    (property "Author" "Antmicro")
    (property "Dielectric" "X5R")
    (property "License" "Apache-2.0")
    (property "MPN" "GRM155R61H104KE14D")
    (property "Manufacturer" "Murata")
    (property "Sheetfile" "psu.kicad_sch")
    (property "Sheetname" "PSU")
    (property "Val" "100n")
    (property "Voltage" "50V")
    (attr smd)
    (fp_text reference "C124" (at 1.71 3.35 180) (layer "B.SilkS")
      (effects (font (size 0.7 0.7) (thickness 0.15)) (justify left bottom mirror))
    )
    (fp_text value "C_100n_0402" (at 0 -1.4 180) (layer "B.Fab")
      (effects (font (size 0.7 0.7) (thickness 0.15)) (justify left bottom mirror))
    )
    (fp_text user "License: Apache-2.0" (at -0.932 -5.17 180) (layer "B.Fab") hide
      (effects (font (size 0.7 0.7) (thickness 0.15)) (justify left bottom mirror))
    )
    (fp_text user "Author: Antmicro" (at -0.932 -4.17 180) (layer "B.Fab") hide
      (effects (font (size 0.7 0.7) (thickness 0.15)) (justify left bottom mirror))
    )
    (fp_text user "${REFERENCE}" (at -0.932 -3.168 180) (layer "B.Fab") hide
      (effects (font (size 0.7 0.7) (thickness 0.15)) (justify left bottom mirror))
    )
    (fp_rect (start -0.94 0.47) (end 0.94 -0.47) (layer "B.CrtYd") (width 0.05) (fill none))
    (fp_rect (start -0.499 0.249) (end 0.499 -0.249) (layer "B.Fab") (width 0.15) (fill none))
    (pad "1" smd roundrect (at -0.484 0) (size 0.59 0.64) (layers "B.Cu" "B.Paste" "B.Mask") (roundrect_rratio 0.25)
      (net 355 "/PSU/G2") (pintype "passive"))
    (pad "2" smd roundrect (at 0.484 0) (size 0.59 0.64) (layers "B.Cu" "B.Paste" "B.Mask") (roundrect_rratio 0.25)
      (net 1 "GND") (pintype "passive"))
  )
	(footprint "sa800u-baseboard-hw-footprints:D_0201_0603Metric" (layer "B.Cu")
    (tedit 62026EA2)
    (at 80.05 139.55 -90)
    (property "Author" "Antmicro")
    (property "License" "Apache-2.0")
    (property "MPN" "PESD18VF1BSFYL")
    (property "Manufacturer" "Nexperia")
    (property "Sheetfile" "usb-pd.kicad_sch")
    (property "Sheetname" "USB-PD")
    (attr smd)
    (fp_text reference "D37" (at -0.89 0.47 90) (layer "B.SilkS")
      (effects (font (size 0.7 0.7) (thickness 0.15)) (justify left bottom mirror))
    )
    (fp_text value "PESD18VF1BSFYL" (at 0 -1.25 90) (layer "B.Fab")
      (effects (font (size 0.7 0.7) (thickness 0.15)) (justify left bottom mirror))
    )
    (fp_text user "License: Apache-2.0" (at -0.72 -5.281 90) (layer "B.Fab") hide
      (effects (font (size 0.7 0.7) (thickness 0.15)) (justify left bottom mirror))
    )
    (fp_text user "Author: Antmicro" (at -0.72 -4.081 90) (layer "B.Fab") hide
      (effects (font (size 0.7 0.7) (thickness 0.15)) (justify left bottom mirror))
    )
    (fp_text user "${REFERENCE}" (at -0.72 -2.882 90) (layer "B.Fab") hide
      (effects (font (size 0.7 0.7) (thickness 0.15)) (justify left bottom mirror))
    )
    (fp_line (start -0.025 0.201) (end -0.025 -0.199) (layer "B.SilkS") (width 0.12))
    (fp_rect (start -0.5 0.3) (end 0.5 -0.3) (layer "B.CrtYd") (width 0.05) (fill none))
    (fp_line (start -0.32 0.172) (end 0.32 0.172) (layer "B.Fab") (width 0.15))
    (fp_line (start -0.32 -0.17) (end 0.32 -0.17) (layer "B.Fab") (width 0.15))
    (fp_line (start 0.32 0.172) (end 0.32 -0.17) (layer "B.Fab") (width 0.15))
    (fp_line (start -0.32 0.172) (end -0.32 -0.17) (layer "B.Fab") (width 0.15))
    (pad "1" smd roundrect (at -0.282 0 270) (size 0.38 0.4) (layers "B.Cu" "B.Paste" "B.Mask") (roundrect_rratio 0.05)
      (net 142 "PD_VDD") (pinfunction "1") (pintype "input"))
    (pad "2" smd rect (at 0.28 0 270) (size 0.38 0.4) (layers "B.Cu" "B.Paste" "B.Mask")
      (net 1 "GND") (pinfunction "2") (pintype "input"))
  )
	(footprint "sa800u-baseboard-hw-footprints:C_0402_1005Metric" (layer "B.Cu")
    (tedit 616D63CF)
    (at 73.6 123.15)
    (descr "Capacitor SMD 0402")
    (tags "capacitor SMD 0402")
    (property "Author" "Antmicro")
    (property "Dielectric" "X5R")
    (property "License" "Apache-2.0")
    (property "MPN" "GRM155R61H104KE14D")
    (property "Manufacturer" "Murata")
    (property "Sheetfile" "psu.kicad_sch")
    (property "Sheetname" "PSU")
    (property "Val" "100n")
    (property "Voltage" "50V")
    (attr smd)
    (fp_text reference "C125" (at 1.71 3.35 180) (layer "B.SilkS")
      (effects (font (size 0.7 0.7) (thickness 0.15)) (justify left bottom mirror))
    )
    (fp_text value "C_100n_0402" (at 0 -1.4 180) (layer "B.Fab")
      (effects (font (size 0.7 0.7) (thickness 0.15)) (justify left bottom mirror))
    )
    (fp_text user "Author: Antmicro" (at -0.932 -4.17 180) (layer "B.Fab") hide
      (effects (font (size 0.7 0.7) (thickness 0.15)) (justify left bottom mirror))
    )
    (fp_text user "License: Apache-2.0" (at -0.932 -5.17 180) (layer "B.Fab") hide
      (effects (font (size 0.7 0.7) (thickness 0.15)) (justify left bottom mirror))
    )
    (fp_text user "${REFERENCE}" (at -0.932 -3.168 180) (layer "B.Fab") hide
      (effects (font (size 0.7 0.7) (thickness 0.15)) (justify left bottom mirror))
    )
    (fp_rect (start -0.94 0.47) (end 0.94 -0.47) (layer "B.CrtYd") (width 0.05) (fill none))
    (fp_rect (start -0.499 0.249) (end 0.499 -0.249) (layer "B.Fab") (width 0.15) (fill none))
    (pad "1" smd roundrect (at -0.484 0) (size 0.59 0.64) (layers "B.Cu" "B.Paste" "B.Mask") (roundrect_rratio 0.25)
      (net 367 "/PSU/G3") (pintype "passive"))
    (pad "2" smd roundrect (at 0.484 0) (size 0.59 0.64) (layers "B.Cu" "B.Paste" "B.Mask") (roundrect_rratio 0.25)
      (net 1 "GND") (pintype "passive"))
  )
)
